# T6G (Grand Teton) — schematic netlist excerpt (pin names and nets, part order shuffled) for the footprints in the layout excerpt that follows; sources: Cadence DE-HDL packaged netlist, KiCad conversion of 04192023_DAF0TMB3IC0_F0TG_MB_C_brd_V02_OCP.brd

PR379  Q_RES  1.5 1% EMPTY  pkg 0402LF  page 206 : A = SW_PVDDIO_P0_SW3_RC ; B = GND
R4482  Q_RES  49.9 1% EMPTY  pkg 0402LF  page 234 : A = USB2_HOST_BMC_B_BUF_DP ; B = GND

(kicad_pcb
	(version 20260206)
	(generator "pcbnew")
	(generator_version "10.0")
	(general
		(thickness 1.6)
		(legacy_teardrops no)
	)
	(paper "A4")
	(title_block
		(title "04192023_DAF0TMB3IC0_F0TG_MB_C_brd_V02_OCP.brd")
		(comment 1 "Grand Teton / footprints 1907-1908 of 8354")
	)
	(layers
		(0 "F.Cu" signal "TOP")
		(4 "In1.Cu" signal "GND")
		(6 "In2.Cu" signal "IN1")
		(8 "In3.Cu" signal "GND1")
		(10 "In4.Cu" signal "IN2")
		(12 "In5.Cu" signal "GND2")
		(14 "In6.Cu" signal "IN3")
		(16 "In7.Cu" signal "GND3")
		(18 "In8.Cu" signal "VCC")
		(20 "In9.Cu" signal "VCC1")
		(22 "In10.Cu" signal "GND4")
		(24 "In11.Cu" signal "IN4")
		(26 "In12.Cu" signal "GND5")
		(28 "In13.Cu" signal "IN5")
		(30 "In14.Cu" signal "GND6")
		(32 "In15.Cu" signal "IN6")
		(34 "In16.Cu" signal "GND7")
		(2 "B.Cu" signal "BOTTOM")
		(9 "F.Adhes" user "F.Adhesive")
		(11 "B.Adhes" user "B.Adhesive")
		(13 "F.Paste" user "Package Geometry/Pastemask Top")
		(15 "B.Paste" user "Package Geometry/Pastemask Bottom")
		(5 "F.SilkS" user "Ref Des/Silkscreen Top")
		(7 "B.SilkS" user "Ref Des/Silkscreen Bottom")
		(1 "F.Mask" user "Board Geometry/Soldermask Top")
		(3 "B.Mask" user "Board Geometry/Soldermask Bottom")
		(17 "Dwgs.User" user "User.Drawings")
		(19 "Cmts.User" user "User.Comments")
		(21 "Eco1.User" user "User.Eco1")
		(23 "Eco2.User" user "User.Eco2")
		(25 "Edge.Cuts" user "Board Geometry/Outline")
		(27 "Margin" user)
		(31 "F.CrtYd" user "Package Geometry/Place Bound Top")
		(29 "B.CrtYd" user "Package Geometry/Place Bound Bottom")
		(35 "F.Fab" user "Ref Des/Assembly Top")
		(33 "B.Fab" user "Ref Des/Assembly Bottom")
	)
	(footprint ""
		(layer "F.Cu")
		(at 14.886178 -107.631484 180)
		(property "Reference" "R4482"
			(at 0 0 180)
			(layer "F.SilkS")
			(hide yes)
			(effects
				(font
					(size 1.27 1.27)
				)
			)
		)
		(property "Value" ""
			(at 0 0 180)
			(layer "F.Fab")
			(effects
				(font
					(size 1.27 1.27)
				)
			)
		)
		(duplicate_pad_numbers_are_jumpers no)
		(fp_line
			(start 0.7874 0.4064)
			(end -0.7874 0.4064)
			(stroke
				(width 0.1524)
				(type default)
			)
			(layer "F.SilkS")
		)
		(fp_line
			(start 0.7874 -0.4064)
			(end 0.7874 0.4064)
			(stroke
				(width 0.1524)
				(type default)
			)
			(layer "F.SilkS")
		)
		(fp_line
			(start -0.7874 0.4064)
			(end -0.7874 -0.4064)
			(stroke
				(width 0.1524)
				(type default)
			)
			(layer "F.SilkS")
		)
		(fp_line
			(start -0.7874 -0.4064)
			(end 0.7874 -0.4064)
			(stroke
				(width 0.1524)
				(type default)
			)
			(layer "F.SilkS")
		)
		(fp_line
			(start 0.67945 0.3048)
			(end 0.120396 0.3048)
			(stroke
				(width 0.1)
				(type default)
			)
			(layer "F.Fab")
		)
		(fp_line
			(start 0.67945 -0.3048)
			(end 0.67945 0.3048)
			(stroke
				(width 0.1)
				(type default)
			)
			(layer "F.Fab")
		)
		(fp_line
			(start 0.12065 -0.2794)
			(end 0.12065 -0.3048)
			(stroke
				(width 0.1)
				(type default)
			)
			(layer "F.Fab")
		)
		(fp_line
			(start 0.12065 -0.3048)
			(end 0.67945 -0.3048)
			(stroke
				(width 0.1)
				(type default)
			)
			(layer "F.Fab")
		)
		(fp_line
			(start 0.120396 0.3048)
			(end 0.120396 0.2794)
			(stroke
				(width 0.1)
				(type default)
			)
			(layer "F.Fab")
		)
		(fp_line
			(start 0.120396 0.2794)
			(end -0.12065 0.2794)
			(stroke
				(width 0.1)
				(type default)
			)
			(layer "F.Fab")
		)
		(fp_line
			(start -0.12065 0.3048)
			(end -0.67945 0.3048)
			(stroke
				(width 0.1)
				(type default)
			)
			(layer "F.Fab")
		)
		(fp_line
			(start -0.12065 0.2794)
			(end -0.12065 0.3048)
			(stroke
				(width 0.1)
				(type default)
			)
			(layer "F.Fab")
		)
		(fp_line
			(start -0.12065 -0.2794)
			(end 0.12065 -0.2794)
			(stroke
				(width 0.1)
				(type default)
			)
			(layer "F.Fab")
		)
		(fp_line
			(start -0.12065 -0.305054)
			(end -0.12065 -0.2794)
			(stroke
				(width 0.1)
				(type default)
			)
			(layer "F.Fab")
		)
		(fp_line
			(start -0.67945 0.3048)
			(end -0.67945 -0.305054)
			(stroke
				(width 0.1)
				(type default)
			)
			(layer "F.Fab")
		)
		(fp_line
			(start -0.67945 -0.305054)
			(end -0.12065 -0.305054)
			(stroke
				(width 0.1)
				(type default)
			)
			(layer "F.Fab")
		)
		(pad "1" smd circle
			(at -0.40005 0 180)
			(size 0 0)
			(layers "F.Cu" "F.Mask" "F.Paste")
			(net "USB2_HOST_BMC_B_BUF_DP")
		)
		(pad "2" smd circle
			(at 0.40005 0 180)
			(size 0 0)
			(layers "F.Cu" "F.Mask" "F.Paste")
			(net "GND")
		)
	)
	(footprint ""
		(layer "F.Cu")
		(at 280.025348 -344.982038 90)
		(property "Reference" "PR379"
			(at 0 0 90)
			(layer "F.SilkS")
			(hide yes)
			(effects
				(font
					(size 1.27 1.27)
				)
			)
		)
		(property "Value" ""
			(at 0 0 90)
			(layer "F.Fab")
			(effects
				(font
					(size 1.27 1.27)
				)
			)
		)
		(duplicate_pad_numbers_are_jumpers no)
		(fp_line
			(start 0.7874 -0.4064)
			(end 0.7874 0.4064)
			(stroke
				(width 0.1524)
				(type default)
			)
			(layer "F.SilkS")
		)
		(fp_line
			(start -0.7874 -0.4064)
			(end 0.7874 -0.4064)
			(stroke
				(width 0.1524)
				(type default)
			)
			(layer "F.SilkS")
		)
		(fp_line
			(start 0.7874 0.4064)
			(end -0.7874 0.4064)
			(stroke
				(width 0.1524)
				(type default)
			)
			(layer "F.SilkS")
		)
		(fp_line
			(start -0.7874 0.4064)
			(end -0.7874 -0.4064)
			(stroke
				(width 0.1524)
				(type default)
			)
			(layer "F.SilkS")
		)
		(fp_line
			(start -0.12065 -0.305054)
			(end -0.12065 -0.2794)
			(stroke
				(width 0.1)
				(type default)
			)
			(layer "F.Fab")
		)
		(fp_line
			(start -0.67945 -0.305054)
			(end -0.12065 -0.305054)
			(stroke
				(width 0.1)
				(type default)
			)
			(layer "F.Fab")
		)
		(fp_line
			(start 0.67945 -0.3048)
			(end 0.67945 0.3048)
			(stroke
				(width 0.1)
				(type default)
			)
			(layer "F.Fab")
		)
		(fp_line
			(start 0.12065 -0.3048)
			(end 0.67945 -0.3048)
			(stroke
				(width 0.1)
				(type default)
			)
			(layer "F.Fab")
		)
		(fp_line
			(start 0.12065 -0.2794)
			(end 0.12065 -0.3048)
			(stroke
				(width 0.1)
				(type default)
			)
			(layer "F.Fab")
		)
		(fp_line
			(start -0.12065 -0.2794)
			(end 0.12065 -0.2794)
			(stroke
				(width 0.1)
				(type default)
			)
			(layer "F.Fab")
		)
		(fp_line
			(start 0.120396 0.2794)
			(end -0.12065 0.2794)
			(stroke
				(width 0.1)
				(type default)
			)
			(layer "F.Fab")
		)
		(fp_line
			(start -0.12065 0.2794)
			(end -0.12065 0.3048)
			(stroke
				(width 0.1)
				(type default)
			)
			(layer "F.Fab")
		)
		(fp_line
			(start 0.67945 0.3048)
			(end 0.120396 0.3048)
			(stroke
				(width 0.1)
				(type default)
			)
			(layer "F.Fab")
		)
		(fp_line
			(start 0.120396 0.3048)
			(end 0.120396 0.2794)
			(stroke
				(width 0.1)
				(type default)
			)
			(layer "F.Fab")
		)
		(fp_line
			(start -0.12065 0.3048)
			(end -0.67945 0.3048)
			(stroke
				(width 0.1)
				(type default)
			)
			(layer "F.Fab")
		)
		(fp_line
			(start -0.67945 0.3048)
			(end -0.67945 -0.305054)
			(stroke
				(width 0.1)
				(type default)
			)
			(layer "F.Fab")
		)
		(pad "1" smd circle
			(at -0.40005 0 90)
			(size 0 0)
			(layers "F.Cu" "F.Mask" "F.Paste")
			(net "SW_PVDDIO_P0_SW3_RC")
		)
		(pad "2" smd circle
			(at 0.40005 0 90)
			(size 0 0)
			(layers "F.Cu" "F.Mask" "F.Paste")
			(net "GND")
		)
	)
)
